FILE_TYPE = MACRO_DRAWING;
SET COLOR_WIRE YELLOW;
SET COLOR_PROP MONO;
SET COLOR_DOT WHITE;
SET COLOR_ARC YELLOW;
SET COLOR_BODY GREEN;
SET COLOR_NOTE MONO;
SET PROP_DISPLAY VALUE;
SET PAGE_NUMBER P237;
FORCEADD OFFPAGE..2
(2975 3650);
FORCEPROP 2 LAST $XR0 235 
J 0
(3164 3650);
DISPLAY 0.638298 (3164 3650);
PAINT MONO (3164 3650);
FORCEPROP 2 LAST BOM_COST P1V8_PCH_STBY_VR
J 0
(3285 3690);
DISPLAY 1.617021 (3285 3690);
PAINT MONO (3285 3690);
DISPLAY INVISIBLE (3285 3690);
FORCEPROP 2 LAST PATH I1
J 0
(3134 3724);
DISPLAY 1.021277 (3134 3724);
PAINT ORANGE (3134 3724);
DISPLAY INVISIBLE (3134 3724);
FORCEPROP 2 LAST CDS_LIB mstr_standard
J 0
(2975 3650);
DISPLAY 1.617021 (2975 3650);
PAINT MONO (2975 3650);
DISPLAY INVISIBLE (2975 3650);
FORCEPROP 2 LAST ROOM P1V8_PCH_STBY_VR
J 0
(2350 3725);
DISPLAY 1.212766 (2350 3725);
PAINT ORANGE (2350 3725);
DISPLAY INVISIBLE (2350 3725);
FORCEPROP 1 LAST OFFPAGE TRUE
J 0
(3300 3525);
PAINT GREEN (3300 3525);
DISPLAY INVISIBLE (3300 3525);
FORCEPROP 1 LAST COMMENT_BODY TRUE
J 0
(2930 3555);
PAINT PEACH (2930 3555);
DISPLAY INVISIBLE (2930 3555);
FORCEADD CAP..1
(3375 2150);
FORCEPROP 1 LAST TOLERANCE 20%
J 0
(3425 2100);
DISPLAY 0.617021 (3425 2100);
PAINT SKYBLUE (3425 2100);
FORCEPROP 1 LAST VOLTAGE 6.3V
J 0
(3425 2150);
DISPLAY 0.617021 (3425 2150);
PAINT SKYBLUE (3425 2150);
FORCEPROP 1 LAST MATERIAL X6S
J 0
(3425 2050);
DISPLAY 0.617021 (3425 2050);
PAINT SKYBLUE (3425 2050);
FORCEPROP 1 LAST VALUE 22UF
J 0
(3425 2200);
DISPLAY 0.617021 (3425 2200);
PAINT SKYBLUE (3425 2200);
FORCEPROP 1 LAST LOCATION C2L45
J 0
(3425 2250);
DISPLAY 0.617021 (3425 2250);
PAINT AQUA (3425 2250);
FORCEPROP 1 LASTPIN (3375 2250) $PN 1
J 0
(3385 2230);
DISPLAY 0.617021 (3385 2230);
PAINT WHITE (3385 2230);
FORCEPROP 1 LASTPIN (3375 2050) $PN 2
J 0
(3385 2030);
DISPLAY 0.617021 (3385 2030);
PAINT WHITE (3385 2030);
FORCEPROP 1 LAST PART_NUMBER C95333-008
J 0
(3425 2000);
DISPLAY 0.617021 (3425 2000);
PAINT BLUE (3425 2000);
FORCEPROP 1 LAST PACK_TYPE 0805
J 0
(3425 1950);
DISPLAY 0.617021 (3425 1950);
PAINT SKYBLUE (3425 1950);
FORCEPROP 2 LAST CDS_SEC 1
J 0
(3425 2350);
DISPLAY 2.276596 (3425 2350);
PAINT ORANGE (3425 2350);
DISPLAY INVISIBLE (3425 2350);
FORCEPROP 2 LAST $SEC 1
J 0
(3425 2350);
DISPLAY 1.510638 (3425 2350);
PAINT MONO (3425 2350);
DISPLAY INVISIBLE (3425 2350);
FORCEPROP 2 LAST ROOM P1V8_PCH_STBY_VR
J 0
(3425 2300);
DISPLAY 1.659574 (3425 2300);
PAINT MONO (3425 2300);
DISPLAY INVISIBLE (3425 2300);
FORCEPROP 2 LAST BOM_COST P1V8_PCH_STBY_VR
J 0
(3425 2300);
DISPLAY 1.659574 (3425 2300);
PAINT MONO (3425 2300);
DISPLAY INVISIBLE (3425 2300);
FORCEPROP 1 LAST PATH I12
J 0
(3425 2300);
DISPLAY 0.978723 (3425 2300);
PAINT WHITE (3425 2300);
DISPLAY INVISIBLE (3425 2300);
FORCEPROP 2 LAST CDS_LOCATION C2L45
J 0
(3425 2250);
DISPLAY 0.617021 (3425 2250);
PAINT AQUA (3425 2250);
DISPLAY INVISIBLE (3425 2250);
FORCEPROP 2 LAST CDS_LIB mstr_discrete
J 0
(3375 2150);
DISPLAY 1.617021 (3375 2150);
PAINT MONO (3375 2150);
DISPLAY INVISIBLE (3375 2150);
FORCEADD CAP..1
(3100 2200);
FORCEPROP 1 LAST PART_NUMBER C95333-008
J 0
(3150 2050);
DISPLAY 0.617021 (3150 2050);
PAINT BLUE (3150 2050);
FORCEPROP 1 LASTPIN (3100 2300) $PN 1
J 0
(3110 2280);
DISPLAY 0.617021 (3110 2280);
PAINT WHITE (3110 2280);
FORCEPROP 1 LAST LOCATION C8A14
J 0
(3150 2300);
DISPLAY 0.617021 (3150 2300);
PAINT AQUA (3150 2300);
FORCEPROP 1 LAST MATERIAL X6S
J 0
(3150 2100);
DISPLAY 0.617021 (3150 2100);
PAINT SKYBLUE (3150 2100);
FORCEPROP 1 LAST VOLTAGE 6.3V
J 0
(3150 2200);
DISPLAY 0.617021 (3150 2200);
PAINT SKYBLUE (3150 2200);
FORCEPROP 1 LAST TOLERANCE 20%
J 0
(3150 2150);
DISPLAY 0.617021 (3150 2150);
PAINT SKYBLUE (3150 2150);
FORCEPROP 1 LASTPIN (3100 2100) $PN 2
J 0
(3110 2080);
DISPLAY 0.617021 (3110 2080);
PAINT WHITE (3110 2080);
FORCEPROP 1 LAST VALUE 22UF
J 0
(3150 2250);
DISPLAY 0.617021 (3150 2250);
PAINT SKYBLUE (3150 2250);
FORCEPROP 1 LAST PACK_TYPE 0805
J 0
(3150 2000);
DISPLAY 0.617021 (3150 2000);
PAINT SKYBLUE (3150 2000);
FORCEPROP 1 LAST PATH I13
J 0
(3150 2350);
DISPLAY 0.978723 (3150 2350);
PAINT WHITE (3150 2350);
DISPLAY INVISIBLE (3150 2350);
FORCEPROP 2 LAST SEC 1
J 0
(3150 2400);
DISPLAY 1.510638 (3150 2400);
PAINT MONO (3150 2400);
DISPLAY INVISIBLE (3150 2400);
FORCEPROP 2 LAST ROOM P1V8_PCH_STBY_VR
J 0
(3150 2350);
DISPLAY 1.659574 (3150 2350);
PAINT MONO (3150 2350);
DISPLAY INVISIBLE (3150 2350);
FORCEPROP 2 LAST BOM_COST P1V8_PCH_STBY_VR
J 0
(3150 2350);
DISPLAY 1.659574 (3150 2350);
PAINT MONO (3150 2350);
DISPLAY INVISIBLE (3150 2350);
FORCEPROP 2 LAST SEC_TYPE 0805
J 0
(3150 2400);
DISPLAY 1.021277 (3150 2400);
PAINT ORANGE (3150 2400);
DISPLAY INVISIBLE (3150 2400);
FORCEPROP 2 LAST CDS_LOCATION C8A14
J 0
(3150 2300);
DISPLAY 0.617021 (3150 2300);
PAINT AQUA (3150 2300);
DISPLAY INVISIBLE (3150 2300);
FORCEPROP 2 LAST CDS_LIB mstr_discrete
J 0
(3100 2200);
DISPLAY 1.617021 (3100 2200);
PAINT MONO (3100 2200);
DISPLAY INVISIBLE (3100 2200);
FORCEADD GND..1
(3500 1400);
FORCEPROP 3 LASTPIN (3500 1450) SIG_NAME GND\g
J 0
(3510 1460);
DISPLAY 0.659574 (3510 1460);
PAINT MONO (3510 1460);
DISPLAY INVISIBLE (3510 1460);
FORCEPROP 2 LAST BOM_COST P1V8_PCH_STBY_VR
J 0
(3100 1475);
DISPLAY 1.659574 (3100 1475);
PAINT MONO (3100 1475);
DISPLAY INVISIBLE (3100 1475);
FORCEPROP 1 LAST PATH I14
J 0
(3575 1400);
DISPLAY 0.872340 (3575 1400);
PAINT AQUA (3575 1400);
DISPLAY INVISIBLE (3575 1400);
FORCEPROP 1 LAST SIZE 1B
J 0
(3575 1350);
DISPLAY 1.489362 (3575 1350);
PAINT GREEN (3575 1350);
DISPLAY INVISIBLE (3575 1350);
FORCEPROP 2 LAST CDS_LIB mstr_symbols
J 0
(3500 1400);
DISPLAY 1.659574 (3500 1400);
PAINT MONO (3500 1400);
DISPLAY INVISIBLE (3500 1400);
FORCEPROP 1 LAST VOLTAGE 0.0V
J 0
(3455 1357);
DISPLAY 0.340426 (3455 1357);
PAINT SKYBLUE (3455 1357);
DISPLAY INVISIBLE (3455 1357);
FORCEPROP 2 LAST ROOM P1V8_PCH_STBY_VR
J 0
(2850 1475);
DISPLAY 1.659574 (2850 1475);
PAINT ORANGE (2850 1475);
DISPLAY INVISIBLE (2850 1475);
FORCEPROP 1 LAST BODY_TYPE PLUMBING
J 0
(3455 1357);
DISPLAY 0.340426 (3455 1357);
PAINT GREEN (3455 1357);
DISPLAY INVISIBLE (3455 1357);
FORCEPROP 1 LAST HDL_POWER GND
J 0
(3500 1550);
DISPLAY 1.489362 (3500 1550);
PAINT GREEN (3500 1550);
DISPLAY INVISIBLE (3500 1550);
FORCEADD RES..2
(2800 2125);
FORCEPROP 1 LAST LOCATION R8A12
J 0
(2845 2250);
DISPLAY 0.617021 (2845 2250);
PAINT AQUA (2845 2250);
FORCEPROP 1 LAST VALUE 475.0
J 0
(2845 2200);
DISPLAY 0.617021 (2845 2200);
PAINT SKYBLUE (2845 2200);
FORCEPROP 1 LAST TOLERANCE 1%
J 0
(2845 2150);
DISPLAY 0.617021 (2845 2150);
PAINT SKYBLUE (2845 2150);
FORCEPROP 1 LAST MATERIAL CHIP
J 0
(2840 2050);
DISPLAY 0.617021 (2840 2050);
PAINT SKYBLUE (2840 2050);
FORCEPROP 1 LAST WATTAGE 1/10W
J 0
(2840 2100);
DISPLAY 0.617021 (2840 2100);
PAINT SKYBLUE (2840 2100);
FORCEPROP 1 LASTPIN (2800 2225) $PN 1
J 0
(2805 2187);
DISPLAY 0.617021 (2805 2187);
PAINT WHITE (2805 2187);
FORCEPROP 1 LASTPIN (2800 2025) $PN 2
J 0
(2805 2035);
DISPLAY 0.617021 (2805 2035);
PAINT WHITE (2805 2035);
FORCEPROP 1 LAST PART_NUMBER G22026-030
J 0
(2840 2000);
DISPLAY 0.617021 (2840 2000);
PAINT BLUE (2840 2000);
FORCEPROP 1 LAST PACK_TYPE 0603
J 0
(2840 1950);
DISPLAY 0.617021 (2840 1950);
PAINT SKYBLUE (2840 1950);
FORCEPROP 2 LAST SEC_TYPE 0603
J 0
(2850 2350);
DISPLAY 1.021277 (2850 2350);
PAINT ORANGE (2850 2350);
DISPLAY INVISIBLE (2850 2350);
FORCEPROP 2 LAST BOM_COST P1V8_PCH_STBY_VR
J 0
(2845 2305);
DISPLAY 1.617021 (2845 2305);
PAINT MONO (2845 2305);
DISPLAY INVISIBLE (2845 2305);
FORCEPROP 2 LAST SEC 1
J 0
(2850 2350);
DISPLAY 0.680851 (2850 2350);
PAINT MONO (2850 2350);
DISPLAY INVISIBLE (2850 2350);
FORCEPROP 2 LAST CDS_LOCATION R8A12
J 0
(2845 2250);
DISPLAY 0.617021 (2845 2250);
PAINT AQUA (2845 2250);
DISPLAY INVISIBLE (2845 2250);
FORCEPROP 1 LAST PATH I15
J 0
(2850 2300);
DISPLAY 0.978723 (2850 2300);
PAINT WHITE (2850 2300);
DISPLAY INVISIBLE (2850 2300);
FORCEPROP 2 LAST ROOM P1V8_PCH_STBY_VR
J 0
(2845 2280);
DISPLAY 1.617021 (2845 2280);
PAINT MONO (2845 2280);
DISPLAY INVISIBLE (2845 2280);
FORCEPROP 2 LAST CDS_LIB mstr_discrete
J 0
(2800 2125);
DISPLAY 1.617021 (2800 2125);
PAINT RED (2800 2125);
DISPLAY INVISIBLE (2800 2125);
FORCEADD CAP..1
(-1975 3150);
FORCEPROP 1 LAST VOLTAGE 6.3V
J 0
(-1925 3150);
DISPLAY 0.617021 (-1925 3150);
PAINT SKYBLUE (-1925 3150);
FORCEPROP 1 LAST TOLERANCE 20%
J 0
(-1925 3100);
DISPLAY 0.617021 (-1925 3100);
PAINT SKYBLUE (-1925 3100);
FORCEPROP 1 LAST VALUE 10UF
J 0
(-1925 3200);
DISPLAY 0.617021 (-1925 3200);
PAINT SKYBLUE (-1925 3200);
FORCEPROP 1 LAST LOCATION C8A6
J 0
(-1925 3250);
DISPLAY 0.617021 (-1925 3250);
PAINT AQUA (-1925 3250);
FORCEPROP 1 LASTPIN (-1975 3250) $PN 1
J 0
(-1965 3230);
DISPLAY 0.617021 (-1965 3230);
PAINT WHITE (-1965 3230);
FORCEPROP 1 LAST MATERIAL X6S
J 0
(-1925 3050);
DISPLAY 0.617021 (-1925 3050);
PAINT SKYBLUE (-1925 3050);
FORCEPROP 1 LAST PACK_TYPE 0603
J 0
(-1925 3000);
DISPLAY 0.617021 (-1925 3000);
PAINT SKYBLUE (-1925 3000);
FORCEPROP 1 LASTPIN (-1975 3050) $PN 2
J 0
(-1965 3030);
DISPLAY 0.617021 (-1965 3030);
PAINT WHITE (-1965 3030);
FORCEPROP 1 LAST PART_NUMBER E15431-002
R 1
J 0
(-2025 2950);
DISPLAY 0.617021 (-2025 2950);
PAINT BLUE (-2025 2950);
FORCEPROP 2 LAST SEC_TYPE 0603
J 0
(-1925 3350);
DISPLAY 1.021277 (-1925 3350);
PAINT ORANGE (-1925 3350);
DISPLAY INVISIBLE (-1925 3350);
FORCEPROP 2 LAST SEC 1
J 0
(-1925 3350);
DISPLAY 0.680851 (-1925 3350);
PAINT MONO (-1925 3350);
DISPLAY INVISIBLE (-1925 3350);
FORCEPROP 1 LAST PATH I29
J 0
(-1925 3300);
DISPLAY 0.978723 (-1925 3300);
PAINT WHITE (-1925 3300);
DISPLAY INVISIBLE (-1925 3300);
FORCEPROP 2 LAST BOM_COST P1V8_PCH_STBY_VR
J 0
(-1915 3285);
DISPLAY 1.617021 (-1915 3285);
PAINT MONO (-1915 3285);
DISPLAY INVISIBLE (-1915 3285);
FORCEPROP 2 LAST ROOM P1V8_PCH_STBY_VR
J 0
(-1915 3285);
DISPLAY 1.617021 (-1915 3285);
PAINT MONO (-1915 3285);
DISPLAY INVISIBLE (-1915 3285);
FORCEPROP 2 LAST CDS_LOCATION C8A6
J 0
(-1925 3250);
DISPLAY 0.617021 (-1925 3250);
PAINT AQUA (-1925 3250);
DISPLAY INVISIBLE (-1925 3250);
FORCEPROP 2 LAST CDS_LIB mstr_discrete
J 0
(-1975 3150);
DISPLAY 1.617021 (-1975 3150);
PAINT MONO (-1975 3150);
DISPLAY INVISIBLE (-1975 3150);
FORCEADD RES..2
(1350 3875);
FORCEPROP 1 LAST LOCATION R8A10
J 0
(1395 4000);
DISPLAY 0.617021 (1395 4000);
PAINT AQUA (1395 4000);
FORCEPROP 1 LAST PART_NUMBER G21796-140
J 0
(1390 3750);
DISPLAY 0.617021 (1390 3750);
PAINT BLUE (1390 3750);
FORCEPROP 1 LAST VALUE 5.11K
J 0
(1395 3950);
DISPLAY 0.617021 (1395 3950);
PAINT SKYBLUE (1395 3950);
FORCEPROP 1 LAST WATTAGE 1/16W
J 0
(1390 3850);
DISPLAY 0.617021 (1390 3850);
PAINT SKYBLUE (1390 3850);
FORCEPROP 1 LAST TOLERANCE 1%
J 0
(1395 3900);
DISPLAY 0.617021 (1395 3900);
PAINT SKYBLUE (1395 3900);
FORCEPROP 1 LASTPIN (1350 3975) $PN 1
J 0
(1355 3937);
DISPLAY 0.617021 (1355 3937);
PAINT WHITE (1355 3937);
FORCEPROP 1 LAST PACK_TYPE 0402
J 0
(1390 3700);
DISPLAY 0.617021 (1390 3700);
PAINT SKYBLUE (1390 3700);
FORCEPROP 1 LASTPIN (1350 3775) $PN 2
J 0
(1355 3785);
DISPLAY 0.617021 (1355 3785);
PAINT WHITE (1355 3785);
FORCEPROP 1 LAST MATERIAL CHIP
J 0
(1390 3800);
DISPLAY 0.617021 (1390 3800);
PAINT SKYBLUE (1390 3800);
FORCEPROP 2 LAST CDS_SEC 1
J 0
(1410 4115);
DISPLAY 1.617021 (1410 4115);
PAINT MONO (1410 4115);
DISPLAY INVISIBLE (1410 4115);
FORCEPROP 2 LAST $SEC 1
J 0
(1410 4115);
DISPLAY 1.617021 (1410 4115);
PAINT MONO (1410 4115);
DISPLAY INVISIBLE (1410 4115);
FORCEPROP 2 LAST BOM_COST P1V8_PCH_STBY_VR
J 0
(1410 4040);
DISPLAY 1.617021 (1410 4040);
PAINT MONO (1410 4040);
DISPLAY INVISIBLE (1410 4040);
FORCEPROP 2 LAST ROOM P1V8_PCH_STBY_VR
J 0
(1410 4040);
DISPLAY 1.617021 (1410 4040);
PAINT MONO (1410 4040);
DISPLAY INVISIBLE (1410 4040);
FORCEPROP 2 LAST CDS_LOCATION R8A10
J 0
(1395 4000);
DISPLAY 0.617021 (1395 4000);
PAINT AQUA (1395 4000);
DISPLAY INVISIBLE (1395 4000);
FORCEPROP 1 LAST PATH I3
J 0
(1400 4050);
DISPLAY 0.978723 (1400 4050);
PAINT WHITE (1400 4050);
DISPLAY INVISIBLE (1400 4050);
FORCEPROP 2 LAST CDS_LIB mstr_discrete
J 0
(1350 3875);
DISPLAY 1.617021 (1350 3875);
PAINT MONO (1350 3875);
DISPLAY INVISIBLE (1350 3875);
FORCEADD GND..1
(-1975 2800);
FORCEPROP 3 LASTPIN (-1975 2850) SIG_NAME GND\g
J 0
(-1965 2860);
DISPLAY 0.659574 (-1965 2860);
PAINT MONO (-1965 2860);
DISPLAY INVISIBLE (-1965 2860);
FORCEPROP 1 LAST PATH I30
J 0
(-1900 2800);
DISPLAY 0.872340 (-1900 2800);
PAINT AQUA (-1900 2800);
DISPLAY INVISIBLE (-1900 2800);
FORCEPROP 2 LAST CDS_LIB mstr_symbols
J 0
(-1975 2800);
DISPLAY 1.617021 (-1975 2800);
PAINT MONO (-1975 2800);
DISPLAY INVISIBLE (-1975 2800);
FORCEPROP 1 LAST SIZE 1B
J 0
(-1900 2750);
DISPLAY 1.042553 (-1900 2750);
PAINT GREEN (-1900 2750);
DISPLAY INVISIBLE (-1900 2750);
FORCEPROP 1 LAST VOLTAGE 0.0V
J 0
(-2020 2757);
DISPLAY 0.340426 (-2020 2757);
PAINT SKYBLUE (-2020 2757);
DISPLAY INVISIBLE (-2020 2757);
FORCEPROP 2 LAST BOM_COST P1V8_PCH_STBY_VR
J 0
(-2290 2895);
DISPLAY 1.617021 (-2290 2895);
PAINT MONO (-2290 2895);
DISPLAY INVISIBLE (-2290 2895);
FORCEPROP 2 LAST ROOM P1V8_PCH_STBY_VR
J 0
(-2625 2875);
DISPLAY 1.212766 (-2625 2875);
PAINT ORANGE (-2625 2875);
DISPLAY INVISIBLE (-2625 2875);
FORCEPROP 1 LAST BODY_TYPE PLUMBING
J 0
(-2020 2757);
DISPLAY 0.340426 (-2020 2757);
PAINT GREEN (-2020 2757);
DISPLAY INVISIBLE (-2020 2757);
FORCEPROP 1 LAST HDL_POWER GND
J 0
(-1975 2950);
DISPLAY 1.042553 (-1975 2950);
PAINT GREEN (-1975 2950);
DISPLAY INVISIBLE (-1975 2950);
FORCEADD CAP..1
(-1550 3175);
FORCEPROP 1 LAST PART_NUMBER 602433-020
J 0
(-1500 3025);
DISPLAY 0.617021 (-1500 3025);
PAINT BLUE (-1500 3025);
FORCEPROP 1 LAST LOCATION C8A4
J 0
(-1500 3275);
DISPLAY 0.617021 (-1500 3275);
PAINT AQUA (-1500 3275);
FORCEPROP 1 LAST VALUE 0.1UF
J 0
(-1500 3225);
DISPLAY 0.617021 (-1500 3225);
PAINT SKYBLUE (-1500 3225);
FORCEPROP 1 LAST TOLERANCE 10%
J 0
(-1500 3125);
DISPLAY 0.617021 (-1500 3125);
PAINT SKYBLUE (-1500 3125);
FORCEPROP 1 LAST VOLTAGE 25V
J 0
(-1500 3175);
DISPLAY 0.617021 (-1500 3175);
PAINT SKYBLUE (-1500 3175);
FORCEPROP 1 LAST MATERIAL X7R
J 0
(-1500 3075);
DISPLAY 0.617021 (-1500 3075);
PAINT SKYBLUE (-1500 3075);
FORCEPROP 1 LASTPIN (-1550 3275) $PN 1
J 0
(-1540 3255);
DISPLAY 0.617021 (-1540 3255);
PAINT WHITE (-1540 3255);
FORCEPROP 1 LASTPIN (-1550 3075) $PN 2
J 0
(-1540 3055);
DISPLAY 0.617021 (-1540 3055);
PAINT WHITE (-1540 3055);
FORCEPROP 1 LAST PACK_TYPE 0603LF
J 0
(-1500 2975);
DISPLAY 0.617021 (-1500 2975);
PAINT SKYBLUE (-1500 2975);
FORCEPROP 2 LAST BOM_COST P1V8_PCH_STBY_VR
J 0
(-1485 3320);
DISPLAY 1.617021 (-1485 3320);
PAINT MONO (-1485 3320);
DISPLAY INVISIBLE (-1485 3320);
FORCEPROP 2 LAST SEC_TYPE 0603LF
J 0
(-1500 3375);
DISPLAY 1.021277 (-1500 3375);
PAINT ORANGE (-1500 3375);
DISPLAY INVISIBLE (-1500 3375);
FORCEPROP 2 LAST SEC 1
J 0
(-1500 3375);
DISPLAY 0.680851 (-1500 3375);
PAINT MONO (-1500 3375);
DISPLAY INVISIBLE (-1500 3375);
FORCEPROP 2 LAST CDS_LOCATION C8A4
J 0
(-1500 3275);
DISPLAY 0.617021 (-1500 3275);
PAINT AQUA (-1500 3275);
DISPLAY INVISIBLE (-1500 3275);
FORCEPROP 1 LAST PATH I31
J 0
(-1500 3325);
DISPLAY 0.978723 (-1500 3325);
PAINT WHITE (-1500 3325);
DISPLAY INVISIBLE (-1500 3325);
FORCEPROP 2 LAST ROOM P1V8_PCH_STBY_VR
J 0
(-1550 3300);
DISPLAY 1.212766 (-1550 3300);
PAINT ORANGE (-1550 3300);
DISPLAY INVISIBLE (-1550 3300);
FORCEPROP 2 LAST CDS_LIB mstr_discrete
J 0
(-1550 3175);
DISPLAY 1.617021 (-1550 3175);
PAINT MONO (-1550 3175);
DISPLAY INVISIBLE (-1550 3175);
FORCEADD GND..1
(-1550 2775);
FORCEPROP 3 LASTPIN (-1550 2825) SIG_NAME GND\g
J 0
(-1540 2835);
DISPLAY 0.659574 (-1540 2835);
PAINT MONO (-1540 2835);
DISPLAY INVISIBLE (-1540 2835);
FORCEPROP 1 LAST SIZE 1B
J 0
(-1475 2725);
DISPLAY 1.042553 (-1475 2725);
PAINT GREEN (-1475 2725);
DISPLAY INVISIBLE (-1475 2725);
FORCEPROP 1 LAST PATH I32
J 0
(-1475 2775);
DISPLAY 0.872340 (-1475 2775);
PAINT AQUA (-1475 2775);
DISPLAY INVISIBLE (-1475 2775);
FORCEPROP 2 LAST CDS_LIB mstr_symbols
J 0
(-1550 2775);
DISPLAY 1.617021 (-1550 2775);
PAINT MONO (-1550 2775);
DISPLAY INVISIBLE (-1550 2775);
FORCEPROP 1 LAST VOLTAGE 0.0V
J 0
(-1595 2732);
DISPLAY 0.340426 (-1595 2732);
PAINT SKYBLUE (-1595 2732);
DISPLAY INVISIBLE (-1595 2732);
FORCEPROP 2 LAST BOM_COST P1V8_PCH_STBY_VR
J 0
(-1860 2870);
DISPLAY 1.617021 (-1860 2870);
PAINT MONO (-1860 2870);
DISPLAY INVISIBLE (-1860 2870);
FORCEPROP 2 LAST ROOM P1V8_PCH_STBY_VR
J 0
(-2200 2850);
DISPLAY 1.212766 (-2200 2850);
PAINT ORANGE (-2200 2850);
DISPLAY INVISIBLE (-2200 2850);
FORCEPROP 1 LAST BODY_TYPE PLUMBING
J 0
(-1595 2732);
DISPLAY 0.340426 (-1595 2732);
PAINT GREEN (-1595 2732);
DISPLAY INVISIBLE (-1595 2732);
FORCEPROP 1 LAST HDL_POWER GND
J 0
(-1550 2925);
DISPLAY 1.042553 (-1550 2925);
PAINT GREEN (-1550 2925);
DISPLAY INVISIBLE (-1550 2925);
FORCEADD P1V8_PCH_STBY..1
(3925 2850);
FORCEPROP 3 LASTPIN (3925 2800) SIG_NAME P1V8_PCH_STBY\g
J 0
(3935 2810);
DISPLAY 0.659574 (3935 2810);
PAINT MONO (3935 2810);
DISPLAY INVISIBLE (3935 2810);
FORCEPROP 2 LAST CDS_LIB mstr_symbols
J 0
(3925 2850);
PAINT ORANGE (3925 2850);
DISPLAY INVISIBLE (3925 2850);
FORCEPROP 2 LAST BOM_COST P1V8_PCH_STBY_VR
J 0
(3950 2950);
DISPLAY 1.659574 (3950 2950);
PAINT MONO (3950 2950);
DISPLAY INVISIBLE (3950 2950);
FORCEPROP 1 LAST PATH I4
J 0
(3975 2875);
DISPLAY 0.872340 (3975 2875);
PAINT AQUA (3975 2875);
DISPLAY INVISIBLE (3975 2875);
FORCEPROP 2 LAST ROOM P1V8_PCH_STBY_VR
J 0
(3950 2950);
DISPLAY 1.659574 (3950 2950);
PAINT ORANGE (3950 2950);
DISPLAY INVISIBLE (3950 2950);
FORCEPROP 1 LAST VOLTAGE 1.8V
J 0
(3880 2807);
DISPLAY 0.340426 (3880 2807);
PAINT SKYBLUE (3880 2807);
DISPLAY INVISIBLE (3880 2807);
FORCEPROP 1 LAST BODY_TYPE PLUMBING
J 0
(3880 2807);
DISPLAY 0.340426 (3880 2807);
PAINT GREEN (3880 2807);
DISPLAY INVISIBLE (3880 2807);
FORCEPROP 1 LAST HDL_POWER P1V8_PCH_STBY
J 1
(3925 2900);
DISPLAY 0.872340 (3925 2900);
PAINT GREEN (3925 2900);
DISPLAY INVISIBLE (3925 2900);
FORCEADD CAP..1
(1350 3475);
FORCEPROP 1 LAST LOCATION C8A11
J 0
(1400 3575);
DISPLAY 0.617021 (1400 3575);
PAINT AQUA (1400 3575);
FORCEPROP 1 LAST PART_NUMBER A36096-046
J 0
(1400 3325);
DISPLAY 0.617021 (1400 3325);
PAINT BLUE (1400 3325);
FORCEPROP 1 LAST VALUE 1000PF
J 0
(1400 3525);
DISPLAY 0.617021 (1400 3525);
PAINT SKYBLUE (1400 3525);
FORCEPROP 1 LAST PACK_TYPE 0402LF
J 0
(1400 3275);
DISPLAY 0.617021 (1400 3275);
PAINT SKYBLUE (1400 3275);
FORCEPROP 1 LAST TOLERANCE 10%
J 0
(1400 3425);
DISPLAY 0.617021 (1400 3425);
PAINT SKYBLUE (1400 3425);
FORCEPROP 1 LAST VOLTAGE 50V
J 0
(1400 3475);
DISPLAY 0.617021 (1400 3475);
PAINT SKYBLUE (1400 3475);
FORCEPROP 1 LAST MATERIAL X7R
J 0
(1400 3375);
DISPLAY 0.617021 (1400 3375);
PAINT SKYBLUE (1400 3375);
FORCEPROP 1 LASTPIN (1350 3375) $PN 2
J 0
(1360 3355);
DISPLAY 0.617021 (1360 3355);
PAINT WHITE (1360 3355);
FORCEPROP 1 LASTPIN (1350 3575) $PN 1
J 0
(1360 3555);
DISPLAY 0.617021 (1360 3555);
PAINT WHITE (1360 3555);
FORCEPROP 2 LAST $SEC 1
J 0
(1410 3690);
DISPLAY 1.617021 (1410 3690);
PAINT MONO (1410 3690);
DISPLAY INVISIBLE (1410 3690);
FORCEPROP 2 LAST ROOM P1V8_PCH_STBY_VR
J 0
(1410 3615);
DISPLAY 1.617021 (1410 3615);
PAINT MONO (1410 3615);
DISPLAY INVISIBLE (1410 3615);
FORCEPROP 2 LAST BOM_COST P1V8_PCH_STBY_VR
J 0
(1410 3615);
DISPLAY 1.617021 (1410 3615);
PAINT MONO (1410 3615);
DISPLAY INVISIBLE (1410 3615);
FORCEPROP 2 LAST CDS_SEC 1
J 0
(1410 3690);
DISPLAY 1.617021 (1410 3690);
PAINT MONO (1410 3690);
DISPLAY INVISIBLE (1410 3690);
FORCEPROP 1 LAST PATH I5
J 0
(1400 3625);
DISPLAY 0.978723 (1400 3625);
PAINT WHITE (1400 3625);
DISPLAY INVISIBLE (1400 3625);
FORCEPROP 2 LAST CDS_LOCATION C8A11
J 0
(1400 3575);
DISPLAY 0.617021 (1400 3575);
PAINT AQUA (1400 3575);
DISPLAY INVISIBLE (1400 3575);
FORCEPROP 2 LAST CDS_LIB mstr_discrete
J 0
(1350 3475);
DISPLAY 1.617021 (1350 3475);
PAINT MONO (1350 3475);
DISPLAY INVISIBLE (1350 3475);
FORCEADD CAP..1
R 2
(-1500 2200);
FORCEPROP 1 LAST PACK_TYPE 0402LF
J 2
(-1550 2000);
DISPLAY 0.617021 (-1550 2000);
PAINT SKYBLUE (-1550 2000);
FORCEPROP 1 LASTPIN (-1500 2100) $PN 2
J 2
(-1510 2080);
DISPLAY 0.617021 (-1510 2080);
PAINT WHITE (-1510 2080);
FORCEPROP 1 LASTPIN (-1500 2300) $PN 1
J 2
(-1510 2280);
DISPLAY 0.617021 (-1510 2280);
PAINT WHITE (-1510 2280);
FORCEPROP 1 LAST VOLTAGE 50V
J 2
(-1550 2200);
DISPLAY 0.617021 (-1550 2200);
PAINT SKYBLUE (-1550 2200);
FORCEPROP 1 LAST TOLERANCE 10%
J 2
(-1550 2150);
DISPLAY 0.617021 (-1550 2150);
PAINT SKYBLUE (-1550 2150);
FORCEPROP 1 LAST MATERIAL EMPTY
J 2
(-1550 2100);
DISPLAY 0.617021 (-1550 2100);
PAINT RED (-1550 2100);
FORCEPROP 1 LAST LOCATION C8A10
J 2
(-1550 2275);
DISPLAY 0.617021 (-1550 2275);
PAINT AQUA (-1550 2275);
FORCEPROP 1 LAST VALUE 1000PF
J 2
(-1550 2225);
DISPLAY 0.617021 (-1550 2225);
PAINT SKYBLUE (-1550 2225);
FORCEPROP 1 LAST PART_NUMBER A36096-046
J 2
(-1550 2050);
DISPLAY 0.617021 (-1550 2050);
PAINT BLUE (-1550 2050);
FORCEPROP 2 LAST CDS_LIB mstr_discrete
J 0
(-1500 2200);
DISPLAY 1.617021 (-1500 2200);
PAINT MONO (-1500 2200);
DISPLAY INVISIBLE (-1500 2200);
FORCEPROP 2 LAST BOM_COST P1V8_PCH_STBY_VR
J 0
(-1575 2325);
DISPLAY 1.659574 (-1575 2325);
PAINT MONO (-1575 2325);
DISPLAY INVISIBLE (-1575 2325);
FORCEPROP 2 LAST CDS_SEC 1
J 0
(-1550 2405);
DISPLAY 2.276596 (-1550 2405);
PAINT ORANGE (-1550 2405);
DISPLAY INVISIBLE (-1550 2405);
FORCEPROP 2 LAST $SEC 1
J 0
(-1550 2405);
DISPLAY 1.510638 (-1550 2405);
PAINT MONO (-1550 2405);
DISPLAY INVISIBLE (-1550 2405);
FORCEPROP 1 LAST PATH I55
J 2
(-1550 2350);
DISPLAY 0.978723 (-1550 2350);
PAINT WHITE (-1550 2350);
DISPLAY INVISIBLE (-1550 2350);
FORCEPROP 2 LAST ROOM P1V8_PCH_STBY_VR
J 2
(-1550 2325);
DISPLAY 1.659574 (-1550 2325);
PAINT ORANGE (-1550 2325);
DISPLAY INVISIBLE (-1550 2325);
FORCEPROP 2 LAST CDS_LOCATION C8A10
J 2
(-1550 2275);
DISPLAY 0.617021 (-1550 2275);
PAINT AQUA (-1550 2275);
DISPLAY INVISIBLE (-1550 2275);
FORCEADD OFFPAGE..1
(-2750 2525);
FORCEPROP 2 LASTPIN (-2700 2525) SIG_NAME PWRGD_P3V3_STBY
J 0
(-2710 2535);
DISPLAY 0.617021 (-2710 2535);
PAINT ORANGE (-2710 2535);
FORCEPROP 2 LAST $XR5 239 
J 0
(-3602 2525);
DISPLAY 0.638298 (-3602 2525);
PAINT MONO (-3602 2525);
FORCEPROP 2 LAST $XR4 196 
J 0
(-3482 2525);
DISPLAY 0.638298 (-3482 2525);
PAINT MONO (-3482 2525);
FORCEPROP 2 LAST $XR3 191 
J 0
(-3362 2525);
DISPLAY 0.638298 (-3362 2525);
PAINT MONO (-3362 2525);
FORCEPROP 2 LAST $XR2 189 
J 0
(-3242 2525);
DISPLAY 0.638298 (-3242 2525);
PAINT MONO (-3242 2525);
FORCEPROP 2 LAST $XR1 101 
J 0
(-3122 2525);
DISPLAY 0.638298 (-3122 2525);
PAINT MONO (-3122 2525);
FORCEPROP 2 LAST $XR0 240 
J 0
(-3002 2525);
DISPLAY 0.638298 (-3002 2525);
PAINT MONO (-3002 2525);
FORCEPROP 2 LAST BOM_COST P1V8_PCH_STBY_VR
J 0
(-3000 2575);
DISPLAY 1.617021 (-3000 2575);
PAINT MONO (-3000 2575);
DISPLAY INVISIBLE (-3000 2575);
FORCEPROP 2 LAST ROOM P1V8_PCH_STBY_VR
J 0
(-3000 2575);
DISPLAY 1.127660 (-3000 2575);
PAINT ORANGE (-3000 2575);
DISPLAY INVISIBLE (-3000 2575);
FORCEPROP 2 LAST PATH I58
J 0
(-2686 2599);
DISPLAY 1.021277 (-2686 2599);
PAINT ORANGE (-2686 2599);
DISPLAY INVISIBLE (-2686 2599);
FORCEPROP 2 LAST CDS_LIB mstr_standard
J 0
(-2750 2525);
DISPLAY 1.617021 (-2750 2525);
PAINT ORANGE (-2750 2525);
DISPLAY INVISIBLE (-2750 2525);
FORCEPROP 1 LAST OFFPAGE TRUE
J 0
(-2425 2400);
PAINT GREEN (-2425 2400);
DISPLAY INVISIBLE (-2425 2400);
FORCEPROP 1 LAST COMMENT_BODY TRUE
J 0
(-2625 2425);
DISPLAY 1.127660 (-2625 2425);
PAINT PEACH (-2625 2425);
DISPLAY INVISIBLE (-2625 2425);
FORCEADD GND..1
(1350 3150);
FORCEPROP 3 LASTPIN (1350 3200) SIG_NAME GND\g
J 0
(1360 3210);
DISPLAY 0.659574 (1360 3210);
PAINT MONO (1360 3210);
DISPLAY INVISIBLE (1360 3210);
FORCEPROP 1 LAST SIZE 1B
J 0
(1425 3100);
DISPLAY 1.042553 (1425 3100);
PAINT GREEN (1425 3100);
DISPLAY INVISIBLE (1425 3100);
FORCEPROP 1 LAST VOLTAGE 0.0V
J 0
(1305 3107);
DISPLAY 0.340426 (1305 3107);
PAINT SKYBLUE (1305 3107);
DISPLAY INVISIBLE (1305 3107);
FORCEPROP 2 LAST CDS_LIB mstr_symbols
J 0
(1350 3150);
DISPLAY 1.617021 (1350 3150);
PAINT MONO (1350 3150);
DISPLAY INVISIBLE (1350 3150);
FORCEPROP 1 LAST PATH I6
J 0
(1425 3150);
DISPLAY 0.872340 (1425 3150);
PAINT AQUA (1425 3150);
DISPLAY INVISIBLE (1425 3150);
FORCEPROP 2 LAST BOM_COST P1V8_PCH_STBY_VR
J 0
(1035 3240);
DISPLAY 1.617021 (1035 3240);
PAINT MONO (1035 3240);
DISPLAY INVISIBLE (1035 3240);
FORCEPROP 2 LAST ROOM P1V8_PCH_STBY_VR
J 0
(700 3225);
DISPLAY 1.212766 (700 3225);
PAINT ORANGE (700 3225);
DISPLAY INVISIBLE (700 3225);
FORCEPROP 1 LAST BODY_TYPE PLUMBING
J 0
(1305 3107);
DISPLAY 0.340426 (1305 3107);
PAINT GREEN (1305 3107);
DISPLAY INVISIBLE (1305 3107);
FORCEPROP 1 LAST HDL_POWER GND
J 0
(1350 3300);
DISPLAY 1.042553 (1350 3300);
PAINT GREEN (1350 3300);
DISPLAY INVISIBLE (1350 3300);
FORCEADD P3V3_STBY..1
(1350 4125);
FORCEPROP 3 LASTPIN (1350 4075) SIG_NAME P3V3_STBY\g
J 0
(1360 4085);
DISPLAY 0.659574 (1360 4085);
PAINT MONO (1360 4085);
DISPLAY INVISIBLE (1360 4085);
FORCEPROP 1 LAST SIZE 1B
J 0
(1395 4147);
DISPLAY 0.340426 (1395 4147);
PAINT GREEN (1395 4147);
DISPLAY INVISIBLE (1395 4147);
FORCEPROP 2 LAST CDS_LIB mstr_symbols
J 0
(1350 4125);
PAINT ORANGE (1350 4125);
DISPLAY INVISIBLE (1350 4125);
FORCEPROP 1 LAST PATH I65
J 0
(1395 4127);
DISPLAY 0.340426 (1395 4127);
PAINT GREEN (1395 4127);
DISPLAY INVISIBLE (1395 4127);
FORCEPROP 1 LAST VOLTAGE 3.3V
J 0
(1305 4082);
DISPLAY 0.340426 (1305 4082);
PAINT SKYBLUE (1305 4082);
DISPLAY INVISIBLE (1305 4082);
FORCEPROP 1 LAST BODY_TYPE PLUMBING
J 0
(1305 4082);
DISPLAY 0.340426 (1305 4082);
PAINT GREEN (1305 4082);
DISPLAY INVISIBLE (1305 4082);
FORCEPROP 1 LAST HDL_POWER P3V3_STBY
J 0
(1050 4000);
DISPLAY 0.872340 (1050 4000);
PAINT ORANGE (1050 4000);
DISPLAY INVISIBLE (1050 4000);
FORCEADD GND..1
(525 2300);
FORCEPROP 3 LASTPIN (525 2350) SIG_NAME GND\g
J 0
(535 2360);
DISPLAY 0.659574 (535 2360);
PAINT MONO (535 2360);
DISPLAY INVISIBLE (535 2360);
FORCEPROP 2 LAST CDS_LIB mstr_symbols
J 0
(525 2300);
PAINT ORANGE (525 2300);
DISPLAY INVISIBLE (525 2300);
FORCEPROP 1 LAST SIZE 1B
J 0
(600 2250);
DISPLAY 1.042553 (600 2250);
PAINT GREEN (600 2250);
DISPLAY INVISIBLE (600 2250);
FORCEPROP 1 LAST PATH I71
J 0
(600 2300);
DISPLAY 0.872340 (600 2300);
PAINT AQUA (600 2300);
DISPLAY INVISIBLE (600 2300);
FORCEPROP 1 LAST VOLTAGE 0.0V
J 0
(480 2257);
DISPLAY 0.340426 (480 2257);
PAINT SKYBLUE (480 2257);
DISPLAY INVISIBLE (480 2257);
FORCEPROP 2 LAST BOM_COST P1V8_PCH_STBY_VR
J 0
(210 2395);
DISPLAY 1.617021 (210 2395);
PAINT MONO (210 2395);
DISPLAY INVISIBLE (210 2395);
FORCEPROP 2 LAST ROOM P1V8_PCH_STBY_VR
J 0
(-125 2375);
DISPLAY 1.212766 (-125 2375);
PAINT ORANGE (-125 2375);
DISPLAY INVISIBLE (-125 2375);
FORCEPROP 1 LAST BODY_TYPE PLUMBING
J 0
(480 2257);
DISPLAY 0.340426 (480 2257);
PAINT GREEN (480 2257);
DISPLAY INVISIBLE (480 2257);
FORCEPROP 1 LAST HDL_POWER GND
J 0
(525 2450);
DISPLAY 1.042553 (525 2450);
PAINT GREEN (525 2450);
DISPLAY INVISIBLE (525 2450);
FORCEADD CAP..1
(3650 2200);
FORCEPROP 1 LAST PART_NUMBER C95333-006
J 0
(3700 2050);
DISPLAY 0.617021 (3700 2050);
PAINT BLUE (3700 2050);
FORCEPROP 1 LAST LOCATION C8A12
J 0
(3700 2300);
DISPLAY 0.617021 (3700 2300);
PAINT AQUA (3700 2300);
FORCEPROP 1 LASTPIN (3650 2300) $PN 1
J 0
(3660 2280);
DISPLAY 0.617021 (3660 2280);
PAINT ORANGE (3660 2280);
FORCEPROP 1 LASTPIN (3650 2100) $PN 2
J 0
(3660 2080);
DISPLAY 0.617021 (3660 2080);
PAINT ORANGE (3660 2080);
FORCEPROP 1 LAST TOLERANCE 20%
J 0
(3700 2150);
DISPLAY 0.617021 (3700 2150);
PAINT SKYBLUE (3700 2150);
FORCEPROP 1 LAST VOLTAGE 4V
J 0
(3700 2200);
DISPLAY 0.617021 (3700 2200);
PAINT SKYBLUE (3700 2200);
FORCEPROP 1 LAST MATERIAL X6S
J 0
(3700 2100);
DISPLAY 0.617021 (3700 2100);
PAINT SKYBLUE (3700 2100);
FORCEPROP 1 LAST VALUE 47UF
J 0
(3700 2250);
DISPLAY 0.617021 (3700 2250);
PAINT SKYBLUE (3700 2250);
FORCEPROP 1 LAST PACK_TYPE 0805
J 0
(3700 2000);
DISPLAY 0.617021 (3700 2000);
PAINT SKYBLUE (3700 2000);
FORCEPROP 2 LAST SEC_TYPE 0805
J 0
(3700 2400);
DISPLAY 1.021277 (3700 2400);
PAINT ORANGE (3700 2400);
DISPLAY INVISIBLE (3700 2400);
FORCEPROP 2 LAST SEC 1
J 0
(3700 2400);
DISPLAY 0.680851 (3700 2400);
PAINT MONO (3700 2400);
DISPLAY INVISIBLE (3700 2400);
FORCEPROP 1 LAST PATH I77
J 0
(3700 2350);
DISPLAY 0.978723 (3700 2350);
PAINT WHITE (3700 2350);
DISPLAY INVISIBLE (3700 2350);
FORCEPROP 2 LAST ROOM P1V8_PCH_STBY_VR
J 0
(3700 2350);
PAINT MONO (3700 2350);
DISPLAY INVISIBLE (3700 2350);
FORCEPROP 2 LAST CDS_LOCATION C8A12
J 0
(3700 2300);
DISPLAY 0.617021 (3700 2300);
PAINT AQUA (3700 2300);
DISPLAY INVISIBLE (3700 2300);
FORCEPROP 2 LAST CDS_LIB mstr_discrete
J 0
(3650 2200);
PAINT ORANGE (3650 2200);
DISPLAY INVISIBLE (3650 2200);
FORCEADD CAP..1
(3900 1850);
FORCEPROP 1 LAST PART_NUMBER C95333-006
J 0
(3950 1700);
DISPLAY 0.617021 (3950 1700);
PAINT BLUE (3950 1700);
FORCEPROP 1 LASTPIN (3900 1950) $PN 1
J 0
(3910 1930);
DISPLAY 0.617021 (3910 1930);
PAINT ORANGE (3910 1930);
FORCEPROP 1 LAST VOLTAGE 4V
J 0
(3950 1850);
DISPLAY 0.617021 (3950 1850);
PAINT SKYBLUE (3950 1850);
FORCEPROP 1 LAST TOLERANCE 20%
J 0
(3950 1800);
DISPLAY 0.617021 (3950 1800);
PAINT SKYBLUE (3950 1800);
FORCEPROP 1 LAST VALUE 47UF
J 0
(3950 1900);
DISPLAY 0.617021 (3950 1900);
PAINT SKYBLUE (3950 1900);
FORCEPROP 1 LAST LOCATION C2L32
J 0
(3950 1950);
DISPLAY 0.617021 (3950 1950);
PAINT AQUA (3950 1950);
FORCEPROP 1 LAST PACK_TYPE 0805
J 0
(3950 1650);
DISPLAY 0.617021 (3950 1650);
PAINT SKYBLUE (3950 1650);
FORCEPROP 1 LAST MATERIAL X6S
J 0
(3950 1750);
DISPLAY 0.617021 (3950 1750);
PAINT SKYBLUE (3950 1750);
FORCEPROP 1 LASTPIN (3900 1750) $PN 2
J 0
(3910 1730);
DISPLAY 0.617021 (3910 1730);
PAINT ORANGE (3910 1730);
FORCEPROP 2 LAST SEC_TYPE 0805
J 0
(3950 2050);
DISPLAY 1.021277 (3950 2050);
PAINT ORANGE (3950 2050);
DISPLAY INVISIBLE (3950 2050);
FORCEPROP 2 LAST SEC 1
J 0
(3950 2050);
DISPLAY 0.680851 (3950 2050);
PAINT MONO (3950 2050);
DISPLAY INVISIBLE (3950 2050);
FORCEPROP 2 LAST ROOM P1V8_PCH_STBY_VR
J 0
(3950 2000);
PAINT MONO (3950 2000);
DISPLAY INVISIBLE (3950 2000);
FORCEPROP 1 LAST PATH I79
J 0
(3950 2000);
DISPLAY 0.978723 (3950 2000);
PAINT WHITE (3950 2000);
DISPLAY INVISIBLE (3950 2000);
FORCEPROP 2 LAST CDS_LOCATION C2L32
J 0
(3950 1950);
DISPLAY 0.617021 (3950 1950);
PAINT AQUA (3950 1950);
DISPLAY INVISIBLE (3950 1950);
FORCEPROP 2 LAST CDS_LIB mstr_discrete
J 0
(3900 1850);
PAINT ORANGE (3900 1850);
DISPLAY INVISIBLE (3900 1850);
FORCEADD RES..2
(2325 1700);
FORCEPROP 1 LAST MATERIAL CHIP
J 0
(2365 1625);
DISPLAY 0.617021 (2365 1625);
PAINT SKYBLUE (2365 1625);
FORCEPROP 1 LAST PART_NUMBER G21796-048
J 0
(2365 1575);
DISPLAY 0.617021 (2365 1575);
PAINT BLUE (2365 1575);
FORCEPROP 1 LAST LOCATION R2L19
J 0
(2370 1825);
DISPLAY 0.617021 (2370 1825);
PAINT AQUA (2370 1825);
FORCEPROP 1 LAST VALUE 49.9K
J 0
(2370 1775);
DISPLAY 0.617021 (2370 1775);
PAINT SKYBLUE (2370 1775);
FORCEPROP 1 LAST WATTAGE 1/16W
J 0
(2365 1675);
DISPLAY 0.617021 (2365 1675);
PAINT SKYBLUE (2365 1675);
FORCEPROP 1 LAST TOLERANCE 1%
J 0
(2370 1725);
DISPLAY 0.617021 (2370 1725);
PAINT SKYBLUE (2370 1725);
FORCEPROP 1 LASTPIN (2325 1800) $PN 1
J 0
(2330 1762);
DISPLAY 0.617021 (2330 1762);
PAINT ORANGE (2330 1762);
FORCEPROP 1 LASTPIN (2325 1600) $PN 2
J 0
(2330 1610);
DISPLAY 0.617021 (2330 1610);
PAINT ORANGE (2330 1610);
FORCEPROP 1 LAST PACK_TYPE 0402
J 0
(2365 1525);
DISPLAY 0.617021 (2365 1525);
PAINT SKYBLUE (2365 1525);
FORCEPROP 2 LAST ROOM P1V8_PCH_STBY_VR
J 0
(2375 1875);
PAINT MONO (2375 1875);
DISPLAY INVISIBLE (2375 1875);
FORCEPROP 2 LAST SEC_TYPE 0402
J 0
(2375 1925);
DISPLAY 1.021277 (2375 1925);
PAINT ORANGE (2375 1925);
DISPLAY INVISIBLE (2375 1925);
FORCEPROP 2 LAST SEC 1
J 0
(2375 1925);
DISPLAY 0.680851 (2375 1925);
PAINT MONO (2375 1925);
DISPLAY INVISIBLE (2375 1925);
FORCEPROP 2 LAST CDS_LOCATION R2L19
J 0
(2370 1825);
DISPLAY 0.617021 (2370 1825);
PAINT AQUA (2370 1825);
DISPLAY INVISIBLE (2370 1825);
FORCEPROP 1 LAST PATH I80
J 0
(2375 1875);
DISPLAY 0.978723 (2375 1875);
PAINT WHITE (2375 1875);
DISPLAY INVISIBLE (2375 1875);
FORCEPROP 2 LAST CDS_LIB mstr_discrete
J 0
(2325 1700);
PAINT ORANGE (2325 1700);
DISPLAY INVISIBLE (2325 1700);
FORCEADD RES..2
(2325 2275);
FORCEPROP 1 LAST PART_NUMBER G21796-327
J 0
(2365 2150);
DISPLAY 0.617021 (2365 2150);
PAINT BLUE (2365 2150);
FORCEPROP 1 LAST VALUE 63.4K
J 0
(2370 2350);
DISPLAY 0.617021 (2370 2350);
PAINT SKYBLUE (2370 2350);
FORCEPROP 1 LAST LOCATION R2L20
J 0
(2370 2400);
DISPLAY 0.617021 (2370 2400);
PAINT AQUA (2370 2400);
FORCEPROP 1 LASTPIN (2325 2375) $PN 1
J 0
(2330 2337);
DISPLAY 0.617021 (2330 2337);
PAINT ORANGE (2330 2337);
FORCEPROP 1 LAST TOLERANCE 1.0%
J 0
(2370 2300);
DISPLAY 0.617021 (2370 2300);
PAINT SKYBLUE (2370 2300);
FORCEPROP 1 LAST WATTAGE 1/16W
J 0
(2365 2250);
DISPLAY 0.617021 (2365 2250);
PAINT SKYBLUE (2365 2250);
FORCEPROP 1 LAST PACK_TYPE 0402
J 0
(2365 2100);
DISPLAY 0.617021 (2365 2100);
PAINT SKYBLUE (2365 2100);
FORCEPROP 1 LAST MATERIAL CHIP
J 0
(2365 2200);
DISPLAY 0.617021 (2365 2200);
PAINT SKYBLUE (2365 2200);
FORCEPROP 1 LASTPIN (2325 2175) $PN 2
J 0
(2330 2185);
DISPLAY 0.617021 (2330 2185);
PAINT ORANGE (2330 2185);
FORCEPROP 1 LAST PATH I81
J 0
(2375 2450);
DISPLAY 0.978723 (2375 2450);
PAINT WHITE (2375 2450);
DISPLAY INVISIBLE (2375 2450);
FORCEPROP 2 LAST CDS_LOCATION R2L20
J 0
(2370 2400);
DISPLAY 0.617021 (2370 2400);
PAINT AQUA (2370 2400);
DISPLAY INVISIBLE (2370 2400);
FORCEPROP 2 LAST SEC 1
J 0
(2375 2500);
DISPLAY 0.680851 (2375 2500);
PAINT MONO (2375 2500);
DISPLAY INVISIBLE (2375 2500);
FORCEPROP 2 LAST ROOM P1V8_PCH_STBY_VR
J 0
(2375 2450);
PAINT MONO (2375 2450);
DISPLAY INVISIBLE (2375 2450);
FORCEPROP 2 LAST SEC_TYPE 0402
J 0
(2375 2500);
DISPLAY 1.021277 (2375 2500);
PAINT ORANGE (2375 2500);
DISPLAY INVISIBLE (2375 2500);
FORCEPROP 2 LAST CDS_LIB mstr_discrete
J 0
(2325 2275);
PAINT ORANGE (2325 2275);
DISPLAY INVISIBLE (2325 2275);
FORCEADD P3V3_STBY..1
(-1750 3650);
FORCEPROP 3 LASTPIN (-1750 3600) SIG_NAME P3V3_STBY\g
J 0
(-1740 3610);
DISPLAY 0.659574 (-1740 3610);
PAINT MONO (-1740 3610);
DISPLAY INVISIBLE (-1740 3610);
FORCEPROP 1 LAST VOLTAGE 3.3V
J 0
(-1795 3607);
DISPLAY 0.340426 (-1795 3607);
PAINT SKYBLUE (-1795 3607);
DISPLAY INVISIBLE (-1795 3607);
FORCEPROP 2 LAST CDS_LIB mstr_symbols
J 0
(-1750 3650);
PAINT MONO (-1750 3650);
DISPLAY INVISIBLE (-1750 3650);
FORCEPROP 1 LAST SIZE 1B
J 0
(-1705 3672);
DISPLAY 0.340426 (-1705 3672);
PAINT GREEN (-1705 3672);
DISPLAY INVISIBLE (-1705 3672);
FORCEPROP 1 LAST PATH I85
J 0
(-1705 3652);
DISPLAY 0.340426 (-1705 3652);
PAINT GREEN (-1705 3652);
DISPLAY INVISIBLE (-1705 3652);
FORCEPROP 1 LAST BODY_TYPE PLUMBING
J 0
(-1795 3607);
DISPLAY 0.340426 (-1795 3607);
PAINT GREEN (-1795 3607);
DISPLAY INVISIBLE (-1795 3607);
FORCEPROP 1 LAST HDL_POWER P3V3_STBY
J 0
(-2050 3525);
DISPLAY 0.872340 (-2050 3525);
PAINT ORANGE (-2050 3525);
DISPLAY INVISIBLE (-2050 3525);
FORCEADD RT9059..1
(-50 2725);
FORCEPROP 2 LASTPIN (450 2425) $PN 11
J 0
(460 2435);
DISPLAY 0.617021 (460 2435);
PAINT ORANGE (460 2435);
FORCEPROP 2 LASTPIN (450 2925) $PN 5
J 0
(460 2935);
DISPLAY 0.617021 (460 2935);
PAINT ORANGE (460 2935);
FORCEPROP 2 LASTPIN (450 2675) $PN 1
J 0
(460 2685);
DISPLAY 0.617021 (460 2685);
PAINT ORANGE (460 2685);
FORCEPROP 2 LASTPIN (450 2725) $PN 2
J 0
(460 2735);
DISPLAY 0.617021 (460 2735);
PAINT ORANGE (460 2735);
FORCEPROP 2 LASTPIN (450 2775) $PN 3
J 0
(460 2785);
DISPLAY 0.617021 (460 2785);
PAINT ORANGE (460 2785);
FORCEPROP 2 LASTPIN (450 2525) $PN 4
J 0
(460 2535);
DISPLAY 0.617021 (460 2535);
PAINT ORANGE (460 2535);
FORCEPROP 1 LAST LOCATION EU8A2
J 0
(-500 3175);
DISPLAY 0.617021 (-500 3175);
PAINT AQUA (-500 3175);
FORCEPROP 1 LAST MATERIAL IC
J 0
(-500 3125);
DISPLAY 0.617021 (-500 3125);
PAINT SKYBLUE (-500 3125);
FORCEPROP 1 LAST PART_NUMBER H65765-001
J 0
(-500 2325);
DISPLAY 0.617021 (-500 2325);
PAINT BLUE (-500 2325);
FORCEPROP 2 LASTPIN (-550 2925) $PN 10
J 2
(-560 2935);
DISPLAY 0.617021 (-560 2935);
PAINT ORANGE (-560 2935);
FORCEPROP 2 LASTPIN (-550 2775) $PN 9
J 2
(-560 2785);
DISPLAY 0.617021 (-560 2785);
PAINT ORANGE (-560 2785);
FORCEPROP 2 LASTPIN (-550 2725) $PN 8
J 2
(-560 2735);
DISPLAY 0.617021 (-560 2735);
PAINT ORANGE (-560 2735);
FORCEPROP 2 LASTPIN (-550 2675) $PN 7
J 2
(-560 2685);
DISPLAY 0.617021 (-560 2685);
PAINT ORANGE (-560 2685);
FORCEPROP 2 LASTPIN (-550 2525) $PN 6
J 2
(-560 2535);
DISPLAY 0.617021 (-560 2535);
PAINT ORANGE (-560 2535);
FORCEPROP 1 LAST PATH I86
J 0
(0 3125);
PAINT GREEN (0 3125);
DISPLAY INVISIBLE (0 3125);
FORCEPROP 1 LAST PACK_TYPE DFN
J 0
(-500 3225);
PAINT SKYBLUE (-500 3225);
DISPLAY INVISIBLE (-500 3225);
FORCEPROP 2 LAST SEC_TYPE DFN
J 0
(-500 3225);
DISPLAY 1.021277 (-500 3225);
PAINT ORANGE (-500 3225);
DISPLAY INVISIBLE (-500 3225);
FORCEPROP 2 LAST SEC 1
J 0
(-500 3225);
DISPLAY 0.680851 (-500 3225);
PAINT MONO (-500 3225);
DISPLAY INVISIBLE (-500 3225);
FORCEPROP 2 LAST CDS_LOCATION EU8A2
J 0
(-500 3175);
DISPLAY 0.617021 (-500 3175);
PAINT AQUA (-500 3175);
DISPLAY INVISIBLE (-500 3175);
FORCEPROP 0 LAST ROOM P1V8_PCH_STBY_VR
J 0
(-500 3275);
DISPLAY 1.021277 (-500 3275);
PAINT ORANGE (-500 3275);
DISPLAY INVISIBLE (-500 3275);
FORCEPROP 2 LAST CDS_LIB mstr_vreg
J 0
(-50 2725);
PAINT MONO (-50 2725);
DISPLAY INVISIBLE (-50 2725);
FORCEADD RES..1
(2175 3650);
FORCEPROP 1 LAST PART_NUMBER G21796-250
J 0
(2125 3750);
DISPLAY 0.617021 (2125 3750);
PAINT BLUE (2125 3750);
FORCEPROP 1 LASTPIN (2275 3650) $PN 2
J 0
(2237 3662);
DISPLAY 0.617021 (2237 3662);
PAINT ORANGE (2237 3662);
FORCEPROP 1 LAST LOCATION R8A11
J 0
(2125 3700);
DISPLAY 0.617021 (2125 3700);
PAINT AQUA (2125 3700);
FORCEPROP 1 LASTPIN (2075 3650) $PN 1
J 0
(2087 3662);
DISPLAY 0.617021 (2087 3662);
PAINT ORANGE (2087 3662);
FORCEPROP 1 LAST TOLERANCE 1.0%
J 0
(2175 3550);
DISPLAY 0.617021 (2175 3550);
PAINT SKYBLUE (2175 3550);
FORCEPROP 1 LAST PACK_TYPE 0402
J 0
(2425 3500);
DISPLAY 0.617021 (2425 3500);
PAINT SKYBLUE (2425 3500);
FORCEPROP 1 LAST MATERIAL CHIP
J 0
(2175 3500);
DISPLAY 0.617021 (2175 3500);
PAINT SKYBLUE (2175 3500);
FORCEPROP 1 LAST VALUE 22.1
J 2
(2150 3550);
DISPLAY 0.617021 (2150 3550);
PAINT SKYBLUE (2150 3550);
FORCEPROP 1 LAST WATTAGE 1/16W
J 2
(2150 3500);
DISPLAY 0.617021 (2150 3500);
PAINT SKYBLUE (2150 3500);
FORCEPROP 0 LAST ROOM P1V8_PCH_STBY_VR
J 0
(2125 3850);
DISPLAY 1.021277 (2125 3850);
PAINT ORANGE (2125 3850);
DISPLAY INVISIBLE (2125 3850);
FORCEPROP 2 LAST SEC 1
J 0
(2125 3850);
DISPLAY 0.680851 (2125 3850);
PAINT MONO (2125 3850);
DISPLAY INVISIBLE (2125 3850);
FORCEPROP 2 LAST SEC_TYPE 0402
J 0
(2125 3850);
DISPLAY 1.021277 (2125 3850);
PAINT ORANGE (2125 3850);
DISPLAY INVISIBLE (2125 3850);
FORCEPROP 1 LAST PATH I90
J 0
(2125 3800);
DISPLAY 0.978723 (2125 3800);
PAINT WHITE (2125 3800);
DISPLAY INVISIBLE (2125 3800);
FORCEPROP 2 LAST CDS_LIB mstr_discrete
J 0
(2175 3650);
PAINT MONO (2175 3650);
DISPLAY INVISIBLE (2175 3650);
FORCEPROP 2 LAST CDS_LOCATION R8A11
J 0
(2125 3700);
DISPLAY 0.617021 (2125 3700);
PAINT AQUA (2125 3700);
DISPLAY INVISIBLE (2125 3700);
FORCEADD GND..1
(2325 1425);
FORCEPROP 3 LASTPIN (2325 1475) SIG_NAME GND\g
J 0
(2335 1485);
DISPLAY 0.659574 (2335 1485);
PAINT MONO (2335 1485);
DISPLAY INVISIBLE (2335 1485);
FORCEPROP 1 LAST VOLTAGE 0.0V
J 0
(2280 1382);
DISPLAY 0.340426 (2280 1382);
PAINT SKYBLUE (2280 1382);
DISPLAY INVISIBLE (2280 1382);
FORCEPROP 1 LAST SIZE 1B
J 0
(2400 1375);
DISPLAY 1.489362 (2400 1375);
PAINT GREEN (2400 1375);
DISPLAY INVISIBLE (2400 1375);
FORCEPROP 2 LAST CDS_LIB mstr_symbols
J 0
(2325 1425);
PAINT MONO (2325 1425);
DISPLAY INVISIBLE (2325 1425);
FORCEPROP 1 LAST PATH I91
J 0
(2400 1425);
DISPLAY 0.872340 (2400 1425);
PAINT AQUA (2400 1425);
DISPLAY INVISIBLE (2400 1425);
FORCEPROP 2 LAST ROOM P1V8_PCH_STBY_VR
J 0
(1675 1500);
DISPLAY 1.659574 (1675 1500);
PAINT ORANGE (1675 1500);
DISPLAY INVISIBLE (1675 1500);
FORCEPROP 2 LAST BOM_COST P1V8_PCH_STBY_VR
J 0
(1925 1500);
DISPLAY 1.659574 (1925 1500);
PAINT MONO (1925 1500);
DISPLAY INVISIBLE (1925 1500);
FORCEPROP 1 LAST BODY_TYPE PLUMBING
J 0
(2280 1382);
DISPLAY 0.340426 (2280 1382);
PAINT GREEN (2280 1382);
DISPLAY INVISIBLE (2280 1382);
FORCEPROP 1 LAST HDL_POWER GND
J 0
(2325 1575);
DISPLAY 1.489362 (2325 1575);
PAINT GREEN (2325 1575);
DISPLAY INVISIBLE (2325 1575);
FORCEADD GND..1
(-1500 1950);
FORCEPROP 3 LASTPIN (-1500 2000) SIG_NAME GND\g
J 0
(-1490 2010);
DISPLAY 0.659574 (-1490 2010);
PAINT MONO (-1490 2010);
DISPLAY INVISIBLE (-1490 2010);
FORCEPROP 2 LAST BOM_COST P1V8_PCH_STBY_VR
J 0
(-1900 2025);
DISPLAY 1.659574 (-1900 2025);
PAINT MONO (-1900 2025);
DISPLAY INVISIBLE (-1900 2025);
FORCEPROP 1 LAST VOLTAGE 0.0V
J 0
(-1545 1907);
DISPLAY 0.340426 (-1545 1907);
PAINT SKYBLUE (-1545 1907);
DISPLAY INVISIBLE (-1545 1907);
FORCEPROP 1 LAST SIZE 1B
J 0
(-1425 1900);
DISPLAY 1.489362 (-1425 1900);
PAINT GREEN (-1425 1900);
DISPLAY INVISIBLE (-1425 1900);
FORCEPROP 2 LAST CDS_LIB mstr_symbols
J 0
(-1500 1950);
PAINT MONO (-1500 1950);
DISPLAY INVISIBLE (-1500 1950);
FORCEPROP 1 LAST PATH I92
J 0
(-1425 1950);
DISPLAY 0.872340 (-1425 1950);
PAINT AQUA (-1425 1950);
DISPLAY INVISIBLE (-1425 1950);
FORCEPROP 2 LAST ROOM P1V8_PCH_STBY_VR
J 0
(-2150 2025);
DISPLAY 1.659574 (-2150 2025);
PAINT ORANGE (-2150 2025);
DISPLAY INVISIBLE (-2150 2025);
FORCEPROP 1 LAST BODY_TYPE PLUMBING
J 0
(-1545 1907);
DISPLAY 0.340426 (-1545 1907);
PAINT GREEN (-1545 1907);
DISPLAY INVISIBLE (-1545 1907);
FORCEPROP 1 LAST HDL_POWER GND
J 0
(-1500 2100);
DISPLAY 1.489362 (-1500 2100);
PAINT GREEN (-1500 2100);
DISPLAY INVISIBLE (-1500 2100);
FORCEADD DESIGN_NOTE..1
(-450 1500);
FORCEPROP 2 LAST CDS_LIB mstr_symbols
J 0
(-450 1500);
PAINT ORANGE (-450 1500);
DISPLAY INVISIBLE (-450 1500);
FORCEPROP 2 LAST BOM_COST SB
J 0
(-650 1450);
DISPLAY 1.361702 (-650 1450);
PAINT ORANGE (-650 1450);
DISPLAY INVISIBLE (-650 1450);
FORCEPROP 1 LAST COMMENT_BODY TRUE
J 0
(-425 1600);
DISPLAY 1.319149 (-425 1600);
PAINT ORANGE (-425 1600);
DISPLAY INVISIBLE (-425 1600);
FORCEADD DESIGN_NOTE..1
(2700 4950);
PAINT SKYBLUE (2700 4950);
FORCEPROP 0 LAST L3 TDC = 0.6 A
J 0
(2550 4650);
DISPLAY 1.170213 (2550 4650);
PAINT WHITE (2550 4650);
FORCEPROP 0 LAST L4 IMAX =1.0 A
J 0
(2550 4575);
DISPLAY 1.170213 (2550 4575);
PAINT WHITE (2550 4575);
FORCEPROP 0 LAST L6 AC TOLERANCE = +- 3.0 %
J 0
(2550 4425);
DISPLAY 1.170213 (2550 4425);
PAINT WHITE (2550 4425);
FORCEPROP 0 LAST L7 DC TOLERANCE = +- 1 %
J 0
(2550 4500);
DISPLAY 1.170213 (2550 4500);
PAINT WHITE (2550 4500);
FORCEPROP 0 LAST L1 P1V8_PCH_STBY VR SPECIFICATION
J 0
(2500 4800);
DISPLAY 1.170213 (2500 4800);
PAINT WHITE (2500 4800);
FORCEPROP 0 LAST L9 DC+AC+RIPPLE = +-5 %
J 0
(2550 4200);
DISPLAY 1.021277 (2550 4200);
PAINT MONO (2550 4200);
FORCEPROP 0 LAST L11 SLEW RATE = 8A/US
J 0
(2550 4125);
DISPLAY 1.021277 (2550 4125);
PAINT MONO (2550 4125);
FORCEPROP 0 LAST L10 STEP LOAD = 0.0035A
J 0
(2550 4050);
DISPLAY 1.021277 (2550 4050);
PAINT MONO (2550 4050);
FORCEPROP 0 LAST L8 RIPPLE TOLERANCE = +- 1 %
J 0
(2550 4275);
DISPLAY 1.021277 (2550 4275);
PAINT MONO (2550 4275);
FORCEPROP 0 LAST L2 VOUT = 1.8 V
J 0
(2550 4725);
DISPLAY 1.170213 (2550 4725);
PAINT WHITE (2550 4725);
FORCEPROP 0 LAST L5 STEP RATE = TBDA/US
J 0
(2550 4350);
DISPLAY 1.170213 (2550 4350);
PAINT WHITE (2550 4350);
FORCEPROP 2 LAST CDS_LIB mstr_symbols
J 0
(2700 4950);
PAINT MONO (2700 4950);
DISPLAY INVISIBLE (2700 4950);
FORCEPROP 2 LAST BOM_COST P1V8_PCH_STBY_VR
J 0
(2100 4875);
DISPLAY 1.042553 (2100 4875);
PAINT ORANGE (2100 4875);
DISPLAY INVISIBLE (2100 4875);
FORCEPROP 2 LAST ROOM P1V8_PCH_STBY_VR
J 0
(2100 4825);
DISPLAY 1.042553 (2100 4825);
PAINT ORANGE (2100 4825);
DISPLAY INVISIBLE (2100 4825);
FORCEPROP 1 LAST COMMENT_BODY TRUE
J 0
(2725 5050);
DISPLAY 0.957447 (2725 5050);
PAINT PEACH (2725 5050);
DISPLAY INVISIBLE (2725 5050);
FORCEADD INTEL_CORP_BPAGE..1
(4250 200);
FORCEPROP 1 LAST CDS_CON_LAST_MODIFIED Fri Jun 16 17:49:24 2017
J 0
(2825 525);
PAINT ORANGE (2825 525);
DISPLAY INVISIBLE (2825 525);
FORCEPROP 1 LAST CUSTOM_TXT_CDS <CURRENT_DESIGN_SHEET> OF <TOTAL_DESIGN_SHEETS>
J 0
(3750 225);
PAINT ORANGE (3750 225);
FORCEPROP 1 LAST CUSTOM_TXT_CDS <CON_LAST_MODIFIED>
J 0
(250 300);
PAINT ORANGE (250 300);
FORCEPROP 2 LAST CUSTOM_TXT_CDS <XR_PAGE_TITLE>
J 0
(-3640 5450);
DISPLAY 0.638298 (-3640 5450);
PAINT PINK (-3640 5450);
DISPLAY INVISIBLE (-3640 5450);
FORCEPROP 1 LAST SCH_TITLE P1V8 PCH STBY VR
J 0
(-3700 250);
DISPLAY 1.212766 (-3700 250);
PAINT ORANGE (-3700 250);
FORCEPROP 2 LAST CDS_LIB mstr_symbols
J 0
(4250 200);
PAINT MONO (4250 200);
DISPLAY INVISIBLE (4250 200);
FORCEPROP 2 LAST PAGE_BORDER TRUE
J 0
(-3640 5450);
DISPLAY 0.638298 (-3640 5450);
PAINT PINK (-3640 5450);
DISPLAY INVISIBLE (-3640 5450);
FORCEPROP 1 LAST COMMENT_BODY TRUE
J 0
(4262 212);
DISPLAY 0.468085 (4262 212);
PAINT GREEN (4262 212);
DISPLAY INVISIBLE (4262 212);
FORCEPROP 2 LAST CDS_XR_PAGE_TITLE CR-237 : @BASEBOARD_FAB2_LIB.BASEBOARD_FAB2(SCH_1):PAGE237
J 0
(-3640 5450);
DISPLAY 0.638298 (-3640 5450);
PAINT PINK (-3640 5450);
DISPLAY INVISIBLE (-3640 5450);
FORCEADD DNS..2
(-1495 2195);
PAINT RED (-1495 2195);
FORCEPROP 2 LAST CDS_LIB mstr_misc
J 0
(-1495 2195);
PAINT ORANGE (-1495 2195);
DISPLAY INVISIBLE (-1495 2195);
FORCEPROP 1 LAST COMMENT_BODY TRUE
R 1
J 0
(-1420 1970);
DISPLAY 0.872340 (-1420 1970);
PAINT GREEN (-1420 1970);
DISPLAY INVISIBLE (-1420 1970);
WIRE 16 -1 (3500 1450)(3500 1575);
WIRE 16 -1 (3375 1575)(3500 1575);
WIRE 16 -1 (3500 1575)(3650 1575);
WIRE 16 -1 (3900 1575)(3650 1575);
WIRE 16 -1 (3650 2100)(3650 1575);
WIRE 16 -1 (3375 1575)(3100 1575);
WIRE 16 -1 (3375 2050)(3375 1575);
WIRE 16 -1 (2800 1575)(3100 1575);
WIRE 16 -1 (3100 2100)(3100 1575);
WIRE 16 -1 (3900 1750)(3900 1575);
WIRE 16 -1 (2800 2025)(2800 1575);
WIRE 16 -1 (-1975 2850)(-1975 3050);
WIRE 16 -1 (-1550 2825)(-1550 3075);
WIRE 16 -1 (3925 2675)(3925 2800);
WIRE 16 -1 (3900 2675)(3925 2675);
WIRE 16 -1 (3900 2675)(3650 2675);
WIRE 16 -1 (3900 1950)(3900 2675);
WIRE 16 -1 (3650 2675)(3375 2675);
WIRE 16 -1 (3650 2300)(3650 2675);
WIRE 16 -1 (3375 2675)(3100 2675);
WIRE 16 -1 (3375 2250)(3375 2675);
WIRE 16 -1 (3100 2675)(2800 2675);
WIRE 16 -1 (3100 2300)(3100 2675);
WIRE 16 -1 (2800 2675)(2325 2675);
WIRE 16 -1 (2800 2225)(2800 2675);
WIRE 16 -1 (2325 2675)(550 2675);
WIRE 16 -1 (2325 2675)(2325 2375);
WIRE 16 -1 (550 2725)(550 2675);
WIRE 16 -1 (550 2675)(450 2675);
WIRE 16 -1 (550 2775)(550 2725);
WIRE 16 -1 (450 2725)(550 2725);
WIRE 16 -1 (450 2775)(550 2775);
WIRE 16 -1 (1350 3200)(1350 3375);
WIRE 16 -1 (1350 4075)(1350 3975);
WIRE 16 -1 (525 2350)(525 2425);
FORCEPROP 0 LAST VOLTAGE 0 V
J 0
(540 2421);
DISPLAY 1.617021 (540 2421);
PAINT SKYBLUE (540 2421);
DISPLAY INVISIBLE (540 2421);
WIRE 16 -1 (525 2425)(450 2425);
WIRE 16 -1 (-1750 3600)(-1750 3400);
WIRE 16 -1 (-1550 3400)(-1750 3400);
WIRE 16 -1 (-1975 3400)(-1750 3400);
WIRE 16 -1 (-1975 3400)(-1975 3250);
WIRE 16 -1 (-1075 3400)(-1550 3400);
WIRE 16 -1 (-1550 3275)(-1550 3400);
WIRE 16 -1 (-1075 2925)(-1075 3400);
WIRE 16 -1 (-1075 2775)(-1075 2925);
WIRE 16 -1 (-1075 2925)(-550 2925);
WIRE 16 -1 (-700 2775)(-1075 2775);
WIRE 16 -1 (-700 2725)(-700 2775);
WIRE 16 -1 (-700 2775)(-550 2775);
WIRE 16 -1 (-700 2675)(-700 2725);
WIRE 16 -1 (-550 2725)(-700 2725);
WIRE 16 -1 (-550 2675)(-700 2675);
WIRE 16 -1 (2325 1600)(2325 1475);
WIRE 16 -1 (-1500 2000)(-1500 2100);
FORCEPROP 0 LAST VOLTAGE 0V
J 0
(-1500 2125);
DISPLAY 1.021277 (-1500 2125);
PAINT SKYBLUE (-1500 2125);
DISPLAY INVISIBLE (-1500 2125);
WIRE 16 -1 (800 1350)(450 1350);
WIRE 16 -1 (800 1350)(800 1050);
WIRE 16 -1 (1150 1350)(800 1350);
WIRE 16 -1 (1925 1350)(1150 1350);
WIRE 16 -1 (1150 1050)(800 1050);
WIRE 16 -1 (1150 1350)(1150 1050);
WIRE 16 -1 (450 1350)(-675 1350);
WIRE 16 -1 (450 1350)(450 1050);
WIRE 16 -1 (800 1050)(450 1050);
WIRE 16 -1 (450 1050)(-675 1050);
WIRE 16 -1 (-675 1350)(-675 1250);
WIRE 16 -1 (1925 1050)(1150 1050);
WIRE 16 -1 (1925 1250)(1925 1350);
WIRE 16 -1 (-675 1250)(1925 1250);
WIRE 16 -1 (1925 1150)(1925 1250);
WIRE 16 -1 (1925 1050)(1925 1150);
WIRE 16 -1 (-675 1250)(-675 1150);
WIRE 16 -1 (-675 1150)(-675 1050);
WIRE 16 -1 (-675 1150)(1925 1150);
WIRE 16 -1 (2925 3650)(2275 3650);
FORCEPROP 2 LAST SIG_NAME PWRGD_P1V8_PCH_STBY
J 0
(2362 3665);
DISPLAY 0.617021 (2362 3665);
PAINT ORANGE (2362 3665);
WIRE 16 -1 (1725 2925)(450 2925);
WIRE 16 -1 (1725 3650)(1725 2925);
WIRE 16 -1 (2075 3650)(1725 3650);
FORCEPROP 2 LAST SIG_NAME PWRGD_P1V8_PCH_STBY_R
J 0
(1512 3665);
DISPLAY 0.617021 (1512 3665);
PAINT ORANGE (1512 3665);
FORCEPROP 2 LASTPROP $XRERR UNIQUE?
J 0
(1272 3665);
DISPLAY 0.638298 (1272 3665);
PAINT MONO (1272 3665);
DISPLAY INVISIBLE (1272 3665);
WIRE 16 -1 (1350 3775)(1350 3650);
WIRE 16 -1 (1725 3650)(1350 3650);
WIRE 16 -1 (1350 3575)(1350 3650);
WIRE 16 -1 (-1500 2525)(-2700 2525);
WIRE 16 -1 (-1500 2300)(-1500 2525);
WIRE 16 -1 (-1500 2525)(-550 2525);
WIRE 16 -1 (2325 1800)(2325 1875);
WIRE 16 -1 (2325 2175)(2325 1875);
WIRE 16 -1 (2325 1875)(850 1875);
FORCEPROP 2 LAST SIG_NAME VR_P1V8_PCH_STBY_FB
J 0
(1227 1895);
DISPLAY 0.617021 (1227 1895);
PAINT ORANGE (1227 1895);
FORCEPROP 2 LASTPROP $XRERR UNIQUE?
J 0
(987 1895);
DISPLAY 0.638298 (987 1895);
PAINT MONO (987 1895);
DISPLAY INVISIBLE (987 1895);
WIRE 16 -1 (850 1875)(850 2525);
WIRE 16 -1 (850 2525)(450 2525);
DOT 1 (-675 1150);
DOT 1 (-675 1250);
DOT 1 (-1500 2525);
DOT 1 (-1075 2925);
DOT 1 (-1550 3400);
DOT 1 (-1750 3400);
DOT 1 (-700 2725);
DOT 1 (-700 2775);
DOT 1 (450 1050);
DOT 1 (450 1350);
DOT 1 (800 1050);
DOT 1 (800 1350);
DOT 1 (1150 1350);
DOT 1 (1150 1050);
DOT 1 (1925 1150);
DOT 1 (1925 1250);
DOT 1 (550 2675);
DOT 1 (550 2725);
DOT 1 (1350 3650);
DOT 1 (1725 3650);
DOT 1 (2325 1875);
DOT 1 (3100 1575);
DOT 1 (3500 1575);
DOT 1 (3375 1575);
DOT 1 (3650 1575);
DOT 1 (2325 2675);
DOT 1 (2800 2675);
DOT 1 (3100 2675);
DOT 1 (3375 2675);
DOT 1 (3650 2675);
DOT 1 (3900 2675);
FORCENOTE
49.9K
(825 1175) 0;
DISPLAY LEFT (825 1175);
DISPLAY 1.276596 (825 1175);
PAINT PURPLE (825 1175);
FORCENOTE
VOLTAGE
(1325 1275) 0;
DISPLAY LEFT (1325 1275);
DISPLAY 0.617021 (1325 1275);
PAINT PURPLE (1325 1275);
FORCENOTE
R2
(2125 1675) 0;
DISPLAY LEFT (2125 1675);
DISPLAY 1.276596 (2125 1675);
PAINT PURPLE (2125 1675);
FORCENOTE
ROOM=P1V8_PCH_STBY_VR
(-3700 450) 0;
DISPLAY LEFT (-3700 450);
DISPLAY 1.276596 (-3700 450);
PAINT PURPLE (-3700 450);
FORCENOTE
BOM COST=P1V8_PCH_STBY_VR
(-3700 375) 0;
DISPLAY LEFT (-3700 375);
DISPLAY 1.276596 (-3700 375);
PAINT PURPLE (-3700 375);
FORCENOTE
PCH
(-250 1275) 0;
DISPLAY LEFT (-250 1275);
DISPLAY 1.276596 (-250 1275);
PAINT PURPLE (-250 1275);
FORCENOTE
WELLSBURG (INTERPOSER)
(-650 1075) 0;
DISPLAY LEFT (-650 1075);
DISPLAY 1.276596 (-650 1075);
PAINT PURPLE (-650 1075);
FORCENOTE
LEWISBURG
(-400 1175) 0;
DISPLAY LEFT (-400 1175);
DISPLAY 1.276596 (-400 1175);
PAINT PURPLE (-400 1175);
FORCENOTE
R1
(600 1275) 0;
DISPLAY LEFT (600 1275);
DISPLAY 1.276596 (600 1275);
PAINT PURPLE (600 1275);
FORCENOTE
43.2K
(525 1075) 0;
DISPLAY LEFT (525 1075);
DISPLAY 1.276596 (525 1075);
PAINT PURPLE (525 1075);
FORCENOTE
63.4K
(525 1175) 0;
DISPLAY LEFT (525 1175);
DISPLAY 1.276596 (525 1175);
PAINT PURPLE (525 1175);
FORCENOTE
49.9K
(825 1075) 0;
DISPLAY LEFT (825 1075);
DISPLAY 1.276596 (825 1075);
PAINT PURPLE (825 1075);
FORCENOTE
R2
(925 1275) 0;
DISPLAY LEFT (925 1275);
DISPLAY 1.276596 (925 1275);
PAINT PURPLE (925 1275);
FORCENOTE
VOLTAGE SETTING
(200 1425) 0;
DISPLAY LEFT (200 1425);
DISPLAY 1.276596 (200 1425);
PAINT PURPLE (200 1425);
FORCENOTE
1.5V
(1425 1075) 0;
DISPLAY LEFT (1425 1075);
DISPLAY 1.276596 (1425 1075);
PAINT PURPLE (1425 1075);
FORCENOTE
1.8V
(1425 1175) 0;
DISPLAY LEFT (1425 1175);
DISPLAY 1.276596 (1425 1175);
PAINT PURPLE (1425 1175);
FORCENOTE
R1
(2125 2250) 0;
DISPLAY LEFT (2125 2250);
DISPLAY 1.276596 (2125 2250);
PAINT PURPLE (2125 2250);
QUIT
